(kicad_pcb
	(version 20260206)
	(generator "pcbnew")
	(generator_version "10.0")
	(general
		(thickness 1.6)
		(legacy_teardrops no)
	)
	(paper "A4")
	(title_block
		(title "pdpb — Lightning_PDPB_BRD.brd")
		(comment 1 "Lightning (Wiwynn / Facebook NVMe JBOF) / footprints 710-717 of 1140")
	)
	(layers
		(0 "F.Cu" signal "TOP")
		(4 "In1.Cu" signal "L2GND")
		(6 "In2.Cu" signal "L3")
		(8 "In3.Cu" signal "L4VCC")
		(10 "In4.Cu" signal "L5VCC")
		(12 "In5.Cu" signal "L6")
		(14 "In6.Cu" signal "L7GND")
		(2 "B.Cu" signal "BOTTOM")
		(9 "F.Adhes" user "F.Adhesive")
		(11 "B.Adhes" user "B.Adhesive")
		(13 "F.Paste" user "Package Geometry/Pastemask Top")
		(15 "B.Paste" user "Package Geometry/Pastemask Bottom")
		(5 "F.SilkS" user "Ref Des/Silkscreen Top")
		(7 "B.SilkS" user "Ref Des/Silkscreen Bottom")
		(1 "F.Mask" user "Board Geometry/Soldermask Top")
		(3 "B.Mask" user "Board Geometry/Soldermask Bottom")
		(17 "Dwgs.User" user "User.Drawings")
		(19 "Cmts.User" user "User.Comments")
		(21 "Eco1.User" user "User.Eco1")
		(23 "Eco2.User" user "User.Eco2")
		(25 "Edge.Cuts" user "Board Geometry/Outline")
		(27 "Margin" user)
		(31 "F.CrtYd" user "Package Geometry/Place Bound Top")
		(29 "B.CrtYd" user "Package Geometry/Place Bound Bottom")
		(35 "F.Fab" user "Ref Des/Assembly Top")
		(33 "B.Fab" user "Ref Des/Assembly Bottom")
	)
	(footprint ""
		(layer "F.Cu")
		(at 25.146 -393.827)
		(property "Reference" "C388"
			(at 0 0 0)
			(layer "F.SilkS")
			(hide yes)
			(effects
				(font
					(size 1.27 1.27)
				)
			)
		)
		(property "Value" "SCD1U25V2KX-2-GP"
			(at 1.1811 -2.7051 0)
			(unlocked yes)
			(layer "F.Fab")
			(hide yes)
			(effects
				(font
					(size 1.016 1.016)
					(thickness 0.1524)
				)
			)
		)
		(property "Device Type" "C402H22"
			(at 1.1811 -4.2291 0)
			(unlocked yes)
			(layer "F.Fab")
			(hide yes)
			(effects
				(font
					(size 1.016 1.016)
					(thickness 0.1524)
				)
			)
		)
		(duplicate_pad_numbers_are_jumpers no)
		(fp_rect
			(start -0.4318 0.9525)
			(end 0.4318 -0.9525)
			(stroke
				(width 0)
				(type default)
			)
			(fill no)
			(layer "F.CrtYd")
		)
		(fp_rect
			(start -0.4318 0.9525)
			(end 0.4318 -0.9525)
			(stroke
				(width 0)
				(type default)
			)
			(fill no)
			(layer "F.Fab")
		)
		(pad "1" smd custom
			(at 0 -0.4445)
			(size 0.1524 0.1524)
			(layers "F.Cu" "F.Mask" "F.Paste")
			(net "P12V")
			(options
				(clearance outline)
				(anchor circle)
			)
			(primitives
				(gr_poly
					(pts
						(arc
							(start 0.3048 -0.2032)
							(mid 0.275042 -0.275042)
							(end 0.2032 -0.3048)
						)
						(arc
							(start -0.2032 -0.3048)
							(mid -0.275042 -0.275042)
							(end -0.3048 -0.2032)
						)
						(arc
							(start -0.3048 0.2032)
							(mid -0.275042 0.275042)
							(end -0.2032 0.3048)
						)
						(arc
							(start 0.2032 0.3048)
							(mid 0.275042 0.275042)
							(end 0.3048 0.2032)
						)
					)
					(width 0)
					(fill yes)
				)
			)
		)
		(pad "2" smd custom
			(at 0 0.4445)
			(size 0.1524 0.1524)
			(layers "F.Cu" "F.Mask" "F.Paste")
			(net "SW_SSD6_N")
			(options
				(clearance outline)
				(anchor circle)
			)
			(primitives
				(gr_poly
					(pts
						(arc
							(start 0.3048 -0.2032)
							(mid 0.275042 -0.275042)
							(end 0.2032 -0.3048)
						)
						(arc
							(start -0.2032 -0.3048)
							(mid -0.275042 -0.275042)
							(end -0.3048 -0.2032)
						)
						(arc
							(start -0.3048 0.2032)
							(mid -0.275042 0.275042)
							(end -0.2032 0.3048)
						)
						(arc
							(start 0.2032 0.3048)
							(mid 0.275042 0.275042)
							(end 0.3048 0.2032)
						)
					)
					(width 0)
					(fill yes)
				)
			)
		)
	)
	(footprint ""
		(layer "F.Cu")
		(at 203.454 -49.022 90)
		(property "Reference" "R334"
			(at 0 0 90)
			(layer "F.SilkS")
			(hide yes)
			(effects
				(font
					(size 1.27 1.27)
				)
			)
		)
		(property "Value" "0R2J-2-GP"
			(at 0.064008 -3.993896 90)
			(unlocked yes)
			(layer "F.Fab")
			(hide yes)
			(effects
				(font
					(size 1.016 1.016)
					(thickness 0.1524)
				)
			)
		)
		(property "Device Type" "R402H16"
			(at 0.064008 -5.517896 90)
			(unlocked yes)
			(layer "F.Fab")
			(hide yes)
			(effects
				(font
					(size 1.016 1.016)
					(thickness 0.1524)
				)
			)
		)
		(duplicate_pad_numbers_are_jumpers no)
		(fp_line
			(start 0.508 -0.9398)
			(end -0.508 -0.9398)
			(stroke
				(width 0.1524)
				(type default)
			)
			(layer "F.SilkS")
		)
		(fp_line
			(start -0.508 -0.9398)
			(end -0.508 0.9398)
			(stroke
				(width 0.1524)
				(type default)
			)
			(layer "F.SilkS")
		)
		(fp_rect
			(start -0.508 0.9398)
			(end 0.508 -0.9398)
			(stroke
				(width 0)
				(type default)
			)
			(fill no)
			(layer "F.CrtYd")
		)
		(fp_rect
			(start -0.508 0.9398)
			(end 0.508 -0.9398)
			(stroke
				(width 0)
				(type default)
			)
			(fill no)
			(layer "F.Fab")
		)
		(pad "1" smd custom
			(at 0 -0.4445 90)
			(size 0.1397 0.1397)
			(layers "F.Cu" "F.Mask" "F.Paste")
			(net "I2C_B_SCL")
			(options
				(clearance outline)
				(anchor circle)
			)
			(primitives
				(gr_poly
					(pts
						(arc
							(start -0.1778 -0.2794)
							(mid -0.249642 -0.249642)
							(end -0.2794 -0.1778)
						)
						(arc
							(start -0.2794 0.1778)
							(mid -0.249642 0.249642)
							(end -0.1778 0.2794)
						)
						(arc
							(start 0.1778 0.2794)
							(mid 0.249642 0.249642)
							(end 0.2794 0.1778)
						)
						(arc
							(start 0.2794 -0.1778)
							(mid 0.249642 -0.249642)
							(end 0.1778 -0.2794)
						)
					)
					(width 0)
					(fill yes)
				)
			)
		)
		(pad "2" smd custom
			(at 0 0.4445 90)
			(size 0.1397 0.1397)
			(layers "F.Cu" "F.Mask" "F.Paste")
			(net "TMP3_SCL")
			(options
				(clearance outline)
				(anchor circle)
			)
			(primitives
				(gr_poly
					(pts
						(arc
							(start -0.1778 -0.2794)
							(mid -0.249642 -0.249642)
							(end -0.2794 -0.1778)
						)
						(arc
							(start -0.2794 0.1778)
							(mid -0.249642 0.249642)
							(end -0.1778 0.2794)
						)
						(arc
							(start 0.1778 0.2794)
							(mid 0.249642 0.249642)
							(end 0.2794 0.1778)
						)
						(arc
							(start 0.2794 -0.1778)
							(mid 0.249642 -0.249642)
							(end 0.1778 -0.2794)
						)
					)
					(width 0)
					(fill yes)
				)
			)
		)
	)
	(footprint ""
		(layer "F.Cu")
		(at 99.06 -293.116 90)
		(property "Reference" "C940"
			(at 0 0 90)
			(layer "F.SilkS")
			(hide yes)
			(effects
				(font
					(size 1.27 1.27)
				)
			)
		)
		(property "Value" "SC1KP50V2KX-1GP"
			(at 1.1811 -2.7051 90)
			(unlocked yes)
			(layer "F.Fab")
			(hide yes)
			(effects
				(font
					(size 1.016 1.016)
					(thickness 0.1524)
				)
			)
		)
		(property "Device Type" "C402H22"
			(at 1.1811 -4.2291 90)
			(unlocked yes)
			(layer "F.Fab")
			(hide yes)
			(effects
				(font
					(size 1.016 1.016)
					(thickness 0.1524)
				)
			)
		)
		(duplicate_pad_numbers_are_jumpers no)
		(fp_rect
			(start -0.4318 0.9525)
			(end 0.4318 -0.9525)
			(stroke
				(width 0)
				(type default)
			)
			(fill no)
			(layer "F.CrtYd")
		)
		(fp_rect
			(start -0.4318 0.9525)
			(end 0.4318 -0.9525)
			(stroke
				(width 0)
				(type default)
			)
			(fill no)
			(layer "F.Fab")
		)
		(pad "1" smd custom
			(at 0 -0.4445 90)
			(size 0.1524 0.1524)
			(layers "F.Cu" "F.Mask" "F.Paste")
			(net "SSD2_CLK0_OE_R_N")
			(options
				(clearance outline)
				(anchor circle)
			)
			(primitives
				(gr_poly
					(pts
						(arc
							(start 0.3048 -0.2032)
							(mid 0.275042 -0.275042)
							(end 0.2032 -0.3048)
						)
						(arc
							(start -0.2032 -0.3048)
							(mid -0.275042 -0.275042)
							(end -0.3048 -0.2032)
						)
						(arc
							(start -0.3048 0.2032)
							(mid -0.275042 0.275042)
							(end -0.2032 0.3048)
						)
						(arc
							(start 0.2032 0.3048)
							(mid 0.275042 0.275042)
							(end 0.3048 0.2032)
						)
					)
					(width 0)
					(fill yes)
				)
			)
		)
		(pad "2" smd custom
			(at 0 0.4445 90)
			(size 0.1524 0.1524)
			(layers "F.Cu" "F.Mask" "F.Paste")
			(net "GND")
			(options
				(clearance outline)
				(anchor circle)
			)
			(primitives
				(gr_poly
					(pts
						(arc
							(start 0.3048 -0.2032)
							(mid 0.275042 -0.275042)
							(end 0.2032 -0.3048)
						)
						(arc
							(start -0.2032 -0.3048)
							(mid -0.275042 -0.275042)
							(end -0.3048 -0.2032)
						)
						(arc
							(start -0.3048 0.2032)
							(mid -0.275042 0.275042)
							(end -0.2032 0.3048)
						)
						(arc
							(start 0.2032 0.3048)
							(mid 0.275042 0.275042)
							(end 0.3048 0.2032)
						)
					)
					(width 0)
					(fill yes)
				)
			)
		)
	)
	(footprint ""
		(layer "F.Cu")
		(at 25.3238 -190.119)
		(property "Reference" "C390"
			(at 0 0 0)
			(layer "F.SilkS")
			(hide yes)
			(effects
				(font
					(size 1.27 1.27)
				)
			)
		)
		(property "Value" "SCD1U25V2KX-2-GP"
			(at 1.1811 -2.7051 0)
			(unlocked yes)
			(layer "F.Fab")
			(hide yes)
			(effects
				(font
					(size 1.016 1.016)
					(thickness 0.1524)
				)
			)
		)
		(property "Device Type" "C402H22"
			(at 1.1811 -4.2291 0)
			(unlocked yes)
			(layer "F.Fab")
			(hide yes)
			(effects
				(font
					(size 1.016 1.016)
					(thickness 0.1524)
				)
			)
		)
		(duplicate_pad_numbers_are_jumpers no)
		(fp_rect
			(start -0.4318 0.9525)
			(end 0.4318 -0.9525)
			(stroke
				(width 0)
				(type default)
			)
			(fill no)
			(layer "F.CrtYd")
		)
		(fp_rect
			(start -0.4318 0.9525)
			(end 0.4318 -0.9525)
			(stroke
				(width 0)
				(type default)
			)
			(fill no)
			(layer "F.Fab")
		)
		(pad "1" smd custom
			(at 0 -0.4445)
			(size 0.1524 0.1524)
			(layers "F.Cu" "F.Mask" "F.Paste")
			(net "P12V")
			(options
				(clearance outline)
				(anchor circle)
			)
			(primitives
				(gr_poly
					(pts
						(arc
							(start 0.3048 -0.2032)
							(mid 0.275042 -0.275042)
							(end 0.2032 -0.3048)
						)
						(arc
							(start -0.2032 -0.3048)
							(mid -0.275042 -0.275042)
							(end -0.3048 -0.2032)
						)
						(arc
							(start -0.3048 0.2032)
							(mid -0.275042 0.275042)
							(end -0.2032 0.3048)
						)
						(arc
							(start 0.2032 0.3048)
							(mid 0.275042 0.275042)
							(end 0.3048 0.2032)
						)
					)
					(width 0)
					(fill yes)
				)
			)
		)
		(pad "2" smd custom
			(at 0 0.4445)
			(size 0.1524 0.1524)
			(layers "F.Cu" "F.Mask" "F.Paste")
			(net "SW_SSD8_N")
			(options
				(clearance outline)
				(anchor circle)
			)
			(primitives
				(gr_poly
					(pts
						(arc
							(start 0.3048 -0.2032)
							(mid 0.275042 -0.275042)
							(end 0.2032 -0.3048)
						)
						(arc
							(start -0.2032 -0.3048)
							(mid -0.275042 -0.275042)
							(end -0.3048 -0.2032)
						)
						(arc
							(start -0.3048 0.2032)
							(mid -0.275042 0.275042)
							(end -0.2032 0.3048)
						)
						(arc
							(start 0.2032 0.3048)
							(mid 0.275042 0.275042)
							(end 0.3048 0.2032)
						)
					)
					(width 0)
					(fill yes)
				)
			)
		)
	)
	(footprint ""
		(layer "F.Cu")
		(at 219.075 -496.1382)
		(property "Reference" "PC1188"
			(at 0 0 0)
			(layer "F.SilkS")
			(hide yes)
			(effects
				(font
					(size 1.27 1.27)
				)
			)
		)
		(property "Value" "SCD01U50V2KX-1GP"
			(at 1.1811 -2.7051 0)
			(unlocked yes)
			(layer "F.Fab")
			(hide yes)
			(effects
				(font
					(size 1.016 1.016)
					(thickness 0.1524)
				)
			)
		)
		(property "Device Type" "C402H22"
			(at 1.1811 -4.2291 0)
			(unlocked yes)
			(layer "F.Fab")
			(hide yes)
			(effects
				(font
					(size 1.016 1.016)
					(thickness 0.1524)
				)
			)
		)
		(duplicate_pad_numbers_are_jumpers no)
		(fp_rect
			(start -0.4318 0.9525)
			(end 0.4318 -0.9525)
			(stroke
				(width 0)
				(type default)
			)
			(fill no)
			(layer "F.CrtYd")
		)
		(fp_rect
			(start -0.4318 0.9525)
			(end 0.4318 -0.9525)
			(stroke
				(width 0)
				(type default)
			)
			(fill no)
			(layer "F.Fab")
		)
		(pad "1" smd custom
			(at 0 -0.4445)
			(size 0.1524 0.1524)
			(layers "F.Cu" "F.Mask" "F.Paste")
			(net "P12V_SSD0")
			(options
				(clearance outline)
				(anchor circle)
			)
			(primitives
				(gr_poly
					(pts
						(arc
							(start 0.3048 -0.2032)
							(mid 0.275042 -0.275042)
							(end 0.2032 -0.3048)
						)
						(arc
							(start -0.2032 -0.3048)
							(mid -0.275042 -0.275042)
							(end -0.3048 -0.2032)
						)
						(arc
							(start -0.3048 0.2032)
							(mid -0.275042 0.275042)
							(end -0.2032 0.3048)
						)
						(arc
							(start 0.2032 0.3048)
							(mid 0.275042 0.275042)
							(end 0.3048 0.2032)
						)
					)
					(width 0)
					(fill yes)
				)
			)
		)
		(pad "2" smd custom
			(at 0 0.4445)
			(size 0.1524 0.1524)
			(layers "F.Cu" "F.Mask" "F.Paste")
			(net "GND")
			(options
				(clearance outline)
				(anchor circle)
			)
			(primitives
				(gr_poly
					(pts
						(arc
							(start 0.3048 -0.2032)
							(mid 0.275042 -0.275042)
							(end 0.2032 -0.3048)
						)
						(arc
							(start -0.2032 -0.3048)
							(mid -0.275042 -0.275042)
							(end -0.3048 -0.2032)
						)
						(arc
							(start -0.3048 0.2032)
							(mid -0.275042 0.275042)
							(end -0.2032 0.3048)
						)
						(arc
							(start 0.2032 0.3048)
							(mid 0.275042 0.275042)
							(end 0.3048 0.2032)
						)
					)
					(width 0)
					(fill yes)
				)
			)
		)
	)
	(footprint ""
		(layer "F.Cu")
		(at 49.53 -13.335 90)
		(property "Reference" "R152"
			(at 0 0 90)
			(layer "F.SilkS")
			(hide yes)
			(effects
				(font
					(size 1.27 1.27)
				)
			)
		)
		(property "Value" "4K7R2J-2-GP"
			(at 0.064008 -3.993896 90)
			(unlocked yes)
			(layer "F.Fab")
			(hide yes)
			(effects
				(font
					(size 1.016 1.016)
					(thickness 0.1524)
				)
			)
		)
		(property "Device Type" "R402H16"
			(at 0.064008 -5.517896 90)
			(unlocked yes)
			(layer "F.Fab")
			(hide yes)
			(effects
				(font
					(size 1.016 1.016)
					(thickness 0.1524)
				)
			)
		)
		(duplicate_pad_numbers_are_jumpers no)
		(fp_line
			(start 0.508 -0.9398)
			(end -0.508 -0.9398)
			(stroke
				(width 0.1524)
				(type default)
			)
			(layer "F.SilkS")
		)
		(fp_line
			(start -0.508 -0.9398)
			(end -0.508 0.9398)
			(stroke
				(width 0.1524)
				(type default)
			)
			(layer "F.SilkS")
		)
		(fp_rect
			(start -0.508 0.9398)
			(end 0.508 -0.9398)
			(stroke
				(width 0)
				(type default)
			)
			(fill no)
			(layer "F.CrtYd")
		)
		(fp_rect
			(start -0.508 0.9398)
			(end 0.508 -0.9398)
			(stroke
				(width 0)
				(type default)
			)
			(fill no)
			(layer "F.Fab")
		)
		(pad "1" smd custom
			(at 0 -0.4445 90)
			(size 0.1397 0.1397)
			(layers "F.Cu" "F.Mask" "F.Paste")
			(net "P12V")
			(options
				(clearance outline)
				(anchor circle)
			)
			(primitives
				(gr_poly
					(pts
						(arc
							(start -0.1778 -0.2794)
							(mid -0.249642 -0.249642)
							(end -0.2794 -0.1778)
						)
						(arc
							(start -0.2794 0.1778)
							(mid -0.249642 0.249642)
							(end -0.1778 0.2794)
						)
						(arc
							(start 0.1778 0.2794)
							(mid 0.249642 0.249642)
							(end 0.2794 0.1778)
						)
						(arc
							(start 0.2794 -0.1778)
							(mid 0.249642 -0.249642)
							(end 0.1778 -0.2794)
						)
					)
					(width 0)
					(fill yes)
				)
			)
		)
		(pad "2" smd custom
			(at 0 0.4445 90)
			(size 0.1397 0.1397)
			(layers "F.Cu" "F.Mask" "F.Paste")
			(net "SW_SSD14_R")
			(options
				(clearance outline)
				(anchor circle)
			)
			(primitives
				(gr_poly
					(pts
						(arc
							(start -0.1778 -0.2794)
							(mid -0.249642 -0.249642)
							(end -0.2794 -0.1778)
						)
						(arc
							(start -0.2794 0.1778)
							(mid -0.249642 0.249642)
							(end -0.1778 0.2794)
						)
						(arc
							(start 0.1778 0.2794)
							(mid 0.249642 0.249642)
							(end 0.2794 0.1778)
						)
						(arc
							(start 0.2794 -0.1778)
							(mid 0.249642 -0.249642)
							(end 0.1778 -0.2794)
						)
					)
					(width 0)
					(fill yes)
				)
			)
		)
	)
	(footprint ""
		(layer "F.Cu")
		(at 89.789 -113.665 -90)
		(property "Reference" "C9345"
			(at 0 0 270)
			(layer "F.SilkS")
			(hide yes)
			(effects
				(font
					(size 1.27 1.27)
				)
			)
		)
		(property "Value" "SC1KP50V2KX-1GP"
			(at 1.1811 -2.7051 270)
			(unlocked yes)
			(layer "F.Fab")
			(hide yes)
			(effects
				(font
					(size 1.016 1.016)
					(thickness 0.1524)
				)
			)
		)
		(property "Device Type" "C402H22"
			(at 1.1811 -4.2291 270)
			(unlocked yes)
			(layer "F.Fab")
			(hide yes)
			(effects
				(font
					(size 1.016 1.016)
					(thickness 0.1524)
				)
			)
		)
		(duplicate_pad_numbers_are_jumpers no)
		(fp_rect
			(start -0.4318 0.9525)
			(end 0.4318 -0.9525)
			(stroke
				(width 0)
				(type default)
			)
			(fill no)
			(layer "F.CrtYd")
		)
		(fp_rect
			(start -0.4318 0.9525)
			(end 0.4318 -0.9525)
			(stroke
				(width 0)
				(type default)
			)
			(fill no)
			(layer "F.Fab")
		)
		(pad "1" smd custom
			(at 0 -0.4445 270)
			(size 0.1524 0.1524)
			(layers "F.Cu" "F.Mask" "F.Paste")
			(net "SSD_PRSNT13")
			(options
				(clearance outline)
				(anchor circle)
			)
			(primitives
				(gr_poly
					(pts
						(arc
							(start 0.3048 -0.2032)
							(mid 0.275042 -0.275042)
							(end 0.2032 -0.3048)
						)
						(arc
							(start -0.2032 -0.3048)
							(mid -0.275042 -0.275042)
							(end -0.3048 -0.2032)
						)
						(arc
							(start -0.3048 0.2032)
							(mid -0.275042 0.275042)
							(end -0.2032 0.3048)
						)
						(arc
							(start 0.2032 0.3048)
							(mid 0.275042 0.275042)
							(end 0.3048 0.2032)
						)
					)
					(width 0)
					(fill yes)
				)
			)
		)
		(pad "2" smd custom
			(at 0 0.4445 270)
			(size 0.1524 0.1524)
			(layers "F.Cu" "F.Mask" "F.Paste")
			(net "GND")
			(options
				(clearance outline)
				(anchor circle)
			)
			(primitives
				(gr_poly
					(pts
						(arc
							(start 0.3048 -0.2032)
							(mid 0.275042 -0.275042)
							(end 0.2032 -0.3048)
						)
						(arc
							(start -0.2032 -0.3048)
							(mid -0.275042 -0.275042)
							(end -0.3048 -0.2032)
						)
						(arc
							(start -0.3048 0.2032)
							(mid -0.275042 0.275042)
							(end -0.2032 0.3048)
						)
						(arc
							(start 0.2032 0.3048)
							(mid 0.275042 0.275042)
							(end 0.3048 0.2032)
						)
					)
					(width 0)
					(fill yes)
				)
			)
		)
	)
	(footprint ""
		(layer "F.Cu")
		(at 32.131 -82.804 -90)
		(property "Reference" "R407"
			(at 0 0 270)
			(layer "F.SilkS")
			(hide yes)
			(effects
				(font
					(size 1.27 1.27)
				)
			)
		)
		(property "Value" "0R2J-2-GP"
			(at 0.064008 -3.993896 270)
			(unlocked yes)
			(layer "F.Fab")
			(hide yes)
			(effects
				(font
					(size 1.016 1.016)
					(thickness 0.1524)
				)
			)
		)
		(property "Device Type" "R402H16"
			(at 0.064008 -5.517896 270)
			(unlocked yes)
			(layer "F.Fab")
			(hide yes)
			(effects
				(font
					(size 1.016 1.016)
					(thickness 0.1524)
				)
			)
		)
		(duplicate_pad_numbers_are_jumpers no)
		(fp_line
			(start -0.508 -0.9398)
			(end -0.508 0.9398)
			(stroke
				(width 0.1524)
				(type default)
			)
			(layer "F.SilkS")
		)
		(fp_line
			(start 0.508 -0.9398)
			(end -0.508 -0.9398)
			(stroke
				(width 0.1524)
				(type default)
			)
			(layer "F.SilkS")
		)
		(fp_rect
			(start -0.508 0.9398)
			(end 0.508 -0.9398)
			(stroke
				(width 0)
				(type default)
			)
			(fill no)
			(layer "F.CrtYd")
		)
		(fp_rect
			(start -0.508 0.9398)
			(end 0.508 -0.9398)
			(stroke
				(width 0)
				(type default)
			)
			(fill no)
			(layer "F.Fab")
		)
		(pad "1" smd custom
			(at 0 -0.4445 270)
			(size 0.1397 0.1397)
			(layers "F.Cu" "F.Mask" "F.Paste")
			(net "SDA_DR9_R")
			(options
				(clearance outline)
				(anchor circle)
			)
			(primitives
				(gr_poly
					(pts
						(arc
							(start -0.1778 -0.2794)
							(mid -0.249642 -0.249642)
							(end -0.2794 -0.1778)
						)
						(arc
							(start -0.2794 0.1778)
							(mid -0.249642 0.249642)
							(end -0.1778 0.2794)
						)
						(arc
							(start 0.1778 0.2794)
							(mid 0.249642 0.249642)
							(end 0.2794 0.1778)
						)
						(arc
							(start 0.2794 -0.1778)
							(mid 0.249642 -0.249642)
							(end 0.1778 -0.2794)
						)
					)
					(width 0)
					(fill yes)
				)
			)
		)
		(pad "2" smd custom
			(at 0 0.4445 270)
			(size 0.1397 0.1397)
			(layers "F.Cu" "F.Mask" "F.Paste")
			(net "SDA_DR9")
			(options
				(clearance outline)
				(anchor circle)
			)
			(primitives
				(gr_poly
					(pts
						(arc
							(start -0.1778 -0.2794)
							(mid -0.249642 -0.249642)
							(end -0.2794 -0.1778)
						)
						(arc
							(start -0.2794 0.1778)
							(mid -0.249642 0.249642)
							(end -0.1778 0.2794)
						)
						(arc
							(start 0.1778 0.2794)
							(mid 0.249642 0.249642)
							(end 0.2794 0.1778)
						)
						(arc
							(start 0.2794 -0.1778)
							(mid 0.249642 -0.249642)
							(end 0.1778 -0.2794)
						)
					)
					(width 0)
					(fill yes)
				)
			)
		)
	)
)
